(kicad_pcb
	(version 20260206)
	(generator "pcbnew")
	(generator_version "10.0")
	(general
		(thickness 1.6)
		(legacy_teardrops no)
	)
	(paper "A4")
	(title_block
		(title "01162023_DA0F0TEBIF0_F0T_Expander_BD_F_brd_V02_OCP.brd")
		(comment 1 "Grand Teton / footprints 1942-1948 of 9728")
	)
	(layers
		(0 "F.Cu" signal "TOP")
		(4 "In1.Cu" signal "GND")
		(6 "In2.Cu" signal "VCC")
		(8 "In3.Cu" signal "VCC1")
		(10 "In4.Cu" signal "GND1")
		(12 "In5.Cu" signal "IN1")
		(14 "In6.Cu" signal "GND2")
		(16 "In7.Cu" signal "IN2")
		(18 "In8.Cu" signal "GND3")
		(20 "In9.Cu" signal "IN3")
		(22 "In10.Cu" signal "GND4")
		(24 "In11.Cu" signal "IN4")
		(26 "In12.Cu" signal "GND5")
		(28 "In13.Cu" signal "IN5")
		(30 "In14.Cu" signal "GND6")
		(32 "In15.Cu" signal "IN6")
		(34 "In16.Cu" signal "GND7")
		(2 "B.Cu" signal "BOTTOM")
		(9 "F.Adhes" user "F.Adhesive")
		(11 "B.Adhes" user "B.Adhesive")
		(13 "F.Paste" user "Package Geometry/Pastemask Top")
		(15 "B.Paste" user "Package Geometry/Pastemask Bottom")
		(5 "F.SilkS" user "Ref Des/Silkscreen Top")
		(7 "B.SilkS" user "Ref Des/Silkscreen Bottom")
		(1 "F.Mask" user "Board Geometry/Soldermask Top")
		(3 "B.Mask" user "Board Geometry/Soldermask Bottom")
		(17 "Dwgs.User" user "User.Drawings")
		(19 "Cmts.User" user "User.Comments")
		(21 "Eco1.User" user "User.Eco1")
		(23 "Eco2.User" user "User.Eco2")
		(25 "Edge.Cuts" user "Board Geometry/Outline")
		(27 "Margin" user)
		(31 "F.CrtYd" user "Package Geometry/Place Bound Top")
		(29 "B.CrtYd" user "Package Geometry/Place Bound Bottom")
		(35 "F.Fab" user "Ref Des/Assembly Top")
		(33 "B.Fab" user "Ref Des/Assembly Bottom")
	)
	(footprint ""
		(layer "F.Cu")
		(at 211.610448 -212.11286 -90)
		(property "Reference" "R4891"
			(at 0 0 270)
			(layer "F.SilkS")
			(hide yes)
			(effects
				(font
					(size 1.27 1.27)
				)
			)
		)
		(property "Value" ""
			(at 0 0 270)
			(layer "F.Fab")
			(effects
				(font
					(size 1.27 1.27)
				)
			)
		)
		(duplicate_pad_numbers_are_jumpers no)
		(fp_line
			(start -0.7874 0.4064)
			(end -0.7874 -0.4064)
			(stroke
				(width 0.1524)
				(type default)
			)
			(layer "F.SilkS")
		)
		(fp_line
			(start 0.7874 0.4064)
			(end -0.7874 0.4064)
			(stroke
				(width 0.1524)
				(type default)
			)
			(layer "F.SilkS")
		)
		(fp_line
			(start -0.7874 -0.4064)
			(end 0.7874 -0.4064)
			(stroke
				(width 0.1524)
				(type default)
			)
			(layer "F.SilkS")
		)
		(fp_line
			(start 0.7874 -0.4064)
			(end 0.7874 0.4064)
			(stroke
				(width 0.1524)
				(type default)
			)
			(layer "F.SilkS")
		)
		(fp_line
			(start -0.67945 0.3048)
			(end -0.67945 -0.305054)
			(stroke
				(width 0.1)
				(type default)
			)
			(layer "F.Fab")
		)
		(fp_line
			(start -0.12065 0.3048)
			(end -0.67945 0.3048)
			(stroke
				(width 0.1)
				(type default)
			)
			(layer "F.Fab")
		)
		(fp_line
			(start 0.120396 0.3048)
			(end 0.120396 0.2794)
			(stroke
				(width 0.1)
				(type default)
			)
			(layer "F.Fab")
		)
		(fp_line
			(start 0.67945 0.3048)
			(end 0.120396 0.3048)
			(stroke
				(width 0.1)
				(type default)
			)
			(layer "F.Fab")
		)
		(fp_line
			(start -0.12065 0.2794)
			(end -0.12065 0.3048)
			(stroke
				(width 0.1)
				(type default)
			)
			(layer "F.Fab")
		)
		(fp_line
			(start 0.120396 0.2794)
			(end -0.12065 0.2794)
			(stroke
				(width 0.1)
				(type default)
			)
			(layer "F.Fab")
		)
		(fp_line
			(start -0.12065 -0.2794)
			(end 0.12065 -0.2794)
			(stroke
				(width 0.1)
				(type default)
			)
			(layer "F.Fab")
		)
		(fp_line
			(start 0.12065 -0.2794)
			(end 0.12065 -0.3048)
			(stroke
				(width 0.1)
				(type default)
			)
			(layer "F.Fab")
		)
		(fp_line
			(start 0.12065 -0.3048)
			(end 0.67945 -0.3048)
			(stroke
				(width 0.1)
				(type default)
			)
			(layer "F.Fab")
		)
		(fp_line
			(start 0.67945 -0.3048)
			(end 0.67945 0.3048)
			(stroke
				(width 0.1)
				(type default)
			)
			(layer "F.Fab")
		)
		(fp_line
			(start -0.67945 -0.305054)
			(end -0.12065 -0.305054)
			(stroke
				(width 0.1)
				(type default)
			)
			(layer "F.Fab")
		)
		(fp_line
			(start -0.12065 -0.305054)
			(end -0.12065 -0.2794)
			(stroke
				(width 0.1)
				(type default)
			)
			(layer "F.Fab")
		)
		(pad "1" smd circle
			(at -0.40005 0 270)
			(size 0 0)
			(layers "F.Cu" "F.Mask" "F.Paste")
			(net "UART_BIC_DEBUG_R_TX")
		)
		(pad "2" smd circle
			(at 0.40005 0 270)
			(size 0 0)
			(layers "F.Cu" "F.Mask" "F.Paste")
			(net "UART_BIC_DEBUG_TX")
		)
	)
	(footprint ""
		(layer "F.Cu")
		(at 393.8397 -356.244906 90)
		(property "Reference" "C755"
			(at 0 0 90)
			(layer "F.SilkS")
			(hide yes)
			(effects
				(font
					(size 1.27 1.27)
				)
			)
		)
		(property "Value" ""
			(at 0 0 90)
			(layer "F.Fab")
			(effects
				(font
					(size 1.27 1.27)
				)
			)
		)
		(duplicate_pad_numbers_are_jumpers no)
		(fp_line
			(start 0.299974 -0.150114)
			(end 0.299974 0.150114)
			(stroke
				(width 0.1)
				(type default)
			)
			(layer "F.Fab")
		)
		(fp_line
			(start -0.299974 -0.150114)
			(end 0.299974 -0.150114)
			(stroke
				(width 0.1)
				(type default)
			)
			(layer "F.Fab")
		)
		(fp_line
			(start 0.299974 0.150114)
			(end -0.299974 0.150114)
			(stroke
				(width 0.1)
				(type default)
			)
			(layer "F.Fab")
		)
		(fp_line
			(start -0.299974 0.150114)
			(end -0.299974 -0.150114)
			(stroke
				(width 0.1)
				(type default)
			)
			(layer "F.Fab")
		)
		(pad "1" smd rect
			(at -0.2667 0 90)
			(size 0.3048 0.381)
			(layers "F.Cu" "F.Mask" "F.Paste")
			(net "P5E_PEX3_STN5_TX_DN<83>")
		)
		(pad "2" smd rect
			(at 0.2667 0 90)
			(size 0.3048 0.381)
			(layers "F.Cu" "F.Mask" "F.Paste")
			(net "P5E_PEX3_STN5_TX_C_DN<83>")
		)
	)
	(footprint ""
		(layer "F.Cu")
		(at 255.867916 -18.437098)
		(property "Reference" "R1693"
			(at 0 0 0)
			(layer "F.SilkS")
			(hide yes)
			(effects
				(font
					(size 1.27 1.27)
				)
			)
		)
		(property "Value" ""
			(at 0 0 0)
			(layer "F.Fab")
			(effects
				(font
					(size 1.27 1.27)
				)
			)
		)
		(duplicate_pad_numbers_are_jumpers no)
		(fp_line
			(start -0.7874 -0.4064)
			(end 0.7874 -0.4064)
			(stroke
				(width 0.1524)
				(type default)
			)
			(layer "F.SilkS")
		)
		(fp_line
			(start -0.7874 0.4064)
			(end -0.7874 -0.4064)
			(stroke
				(width 0.1524)
				(type default)
			)
			(layer "F.SilkS")
		)
		(fp_line
			(start 0.7874 -0.4064)
			(end 0.7874 0.4064)
			(stroke
				(width 0.1524)
				(type default)
			)
			(layer "F.SilkS")
		)
		(fp_line
			(start 0.7874 0.4064)
			(end -0.7874 0.4064)
			(stroke
				(width 0.1524)
				(type default)
			)
			(layer "F.SilkS")
		)
		(fp_line
			(start -0.67945 -0.305054)
			(end -0.12065 -0.305054)
			(stroke
				(width 0.1)
				(type default)
			)
			(layer "F.Fab")
		)
		(fp_line
			(start -0.67945 0.3048)
			(end -0.67945 -0.305054)
			(stroke
				(width 0.1)
				(type default)
			)
			(layer "F.Fab")
		)
		(fp_line
			(start -0.12065 -0.305054)
			(end -0.12065 -0.2794)
			(stroke
				(width 0.1)
				(type default)
			)
			(layer "F.Fab")
		)
		(fp_line
			(start -0.12065 -0.2794)
			(end 0.12065 -0.2794)
			(stroke
				(width 0.1)
				(type default)
			)
			(layer "F.Fab")
		)
		(fp_line
			(start -0.12065 0.2794)
			(end -0.12065 0.3048)
			(stroke
				(width 0.1)
				(type default)
			)
			(layer "F.Fab")
		)
		(fp_line
			(start -0.12065 0.3048)
			(end -0.67945 0.3048)
			(stroke
				(width 0.1)
				(type default)
			)
			(layer "F.Fab")
		)
		(fp_line
			(start 0.120396 0.2794)
			(end -0.12065 0.2794)
			(stroke
				(width 0.1)
				(type default)
			)
			(layer "F.Fab")
		)
		(fp_line
			(start 0.120396 0.3048)
			(end 0.120396 0.2794)
			(stroke
				(width 0.1)
				(type default)
			)
			(layer "F.Fab")
		)
		(fp_line
			(start 0.12065 -0.3048)
			(end 0.67945 -0.3048)
			(stroke
				(width 0.1)
				(type default)
			)
			(layer "F.Fab")
		)
		(fp_line
			(start 0.12065 -0.2794)
			(end 0.12065 -0.3048)
			(stroke
				(width 0.1)
				(type default)
			)
			(layer "F.Fab")
		)
		(fp_line
			(start 0.67945 -0.3048)
			(end 0.67945 0.3048)
			(stroke
				(width 0.1)
				(type default)
			)
			(layer "F.Fab")
		)
		(fp_line
			(start 0.67945 0.3048)
			(end 0.120396 0.3048)
			(stroke
				(width 0.1)
				(type default)
			)
			(layer "F.Fab")
		)
		(pad "1" smd circle
			(at -0.40005 0)
			(size 0 0)
			(layers "F.Cu" "F.Mask" "F.Paste")
			(net "SMB_ISO_SSD8_R_SCL")
		)
		(pad "2" smd circle
			(at 0.40005 0)
			(size 0 0)
			(layers "F.Cu" "F.Mask" "F.Paste")
			(net "SMB_ISO_SSD8_SCL")
		)
	)
	(footprint ""
		(layer "F.Cu")
		(at 204.752194 -112.860836 180)
		(property "Reference" "PC797"
			(at 0 0 180)
			(layer "F.SilkS")
			(hide yes)
			(effects
				(font
					(size 1.27 1.27)
				)
			)
		)
		(property "Value" ""
			(at 0 0 180)
			(layer "F.Fab")
			(effects
				(font
					(size 1.27 1.27)
				)
			)
		)
		(duplicate_pad_numbers_are_jumpers no)
		(fp_line
			(start 0.7874 0.4064)
			(end -0.7874 0.4064)
			(stroke
				(width 0.1524)
				(type default)
			)
			(layer "F.SilkS")
		)
		(fp_line
			(start 0.7874 -0.4064)
			(end 0.7874 0.4064)
			(stroke
				(width 0.1524)
				(type default)
			)
			(layer "F.SilkS")
		)
		(fp_line
			(start -0.7874 0.4064)
			(end -0.7874 -0.4064)
			(stroke
				(width 0.1524)
				(type default)
			)
			(layer "F.SilkS")
		)
		(fp_line
			(start -0.7874 -0.4064)
			(end 0.7874 -0.4064)
			(stroke
				(width 0.1524)
				(type default)
			)
			(layer "F.SilkS")
		)
		(fp_line
			(start 0.67945 0.3048)
			(end 0.120396 0.3048)
			(stroke
				(width 0.1)
				(type default)
			)
			(layer "F.Fab")
		)
		(fp_line
			(start 0.67945 -0.3048)
			(end 0.67945 0.3048)
			(stroke
				(width 0.1)
				(type default)
			)
			(layer "F.Fab")
		)
		(fp_line
			(start 0.12065 -0.2794)
			(end 0.12065 -0.3048)
			(stroke
				(width 0.1)
				(type default)
			)
			(layer "F.Fab")
		)
		(fp_line
			(start 0.12065 -0.3048)
			(end 0.67945 -0.3048)
			(stroke
				(width 0.1)
				(type default)
			)
			(layer "F.Fab")
		)
		(fp_line
			(start 0.120396 0.3048)
			(end 0.120396 0.2794)
			(stroke
				(width 0.1)
				(type default)
			)
			(layer "F.Fab")
		)
		(fp_line
			(start 0.120396 0.2794)
			(end -0.12065 0.2794)
			(stroke
				(width 0.1)
				(type default)
			)
			(layer "F.Fab")
		)
		(fp_line
			(start -0.12065 0.3048)
			(end -0.67945 0.3048)
			(stroke
				(width 0.1)
				(type default)
			)
			(layer "F.Fab")
		)
		(fp_line
			(start -0.12065 0.2794)
			(end -0.12065 0.3048)
			(stroke
				(width 0.1)
				(type default)
			)
			(layer "F.Fab")
		)
		(fp_line
			(start -0.12065 -0.2794)
			(end 0.12065 -0.2794)
			(stroke
				(width 0.1)
				(type default)
			)
			(layer "F.Fab")
		)
		(fp_line
			(start -0.12065 -0.305054)
			(end -0.12065 -0.2794)
			(stroke
				(width 0.1)
				(type default)
			)
			(layer "F.Fab")
		)
		(fp_line
			(start -0.67945 0.3048)
			(end -0.67945 -0.305054)
			(stroke
				(width 0.1)
				(type default)
			)
			(layer "F.Fab")
		)
		(fp_line
			(start -0.67945 -0.305054)
			(end -0.12065 -0.305054)
			(stroke
				(width 0.1)
				(type default)
			)
			(layer "F.Fab")
		)
		(pad "1" smd circle
			(at -0.40005 0 180)
			(size 0 0)
			(layers "F.Cu" "F.Mask" "F.Paste")
			(net "P3V3_NIC3_CO_DV_DT")
		)
		(pad "2" smd circle
			(at 0.40005 0 180)
			(size 0 0)
			(layers "F.Cu" "F.Mask" "F.Paste")
			(net "GND")
		)
	)
	(footprint ""
		(layer "F.Cu")
		(at 65.370202 -343.952322 90)
		(property "Reference" "C126"
			(at 0 0 90)
			(layer "F.SilkS")
			(hide yes)
			(effects
				(font
					(size 1.27 1.27)
				)
			)
		)
		(property "Value" ""
			(at 0 0 90)
			(layer "F.Fab")
			(effects
				(font
					(size 1.27 1.27)
				)
			)
		)
		(duplicate_pad_numbers_are_jumpers no)
		(fp_line
			(start 0.299974 -0.150114)
			(end 0.299974 0.150114)
			(stroke
				(width 0.1)
				(type default)
			)
			(layer "F.Fab")
		)
		(fp_line
			(start -0.299974 -0.150114)
			(end 0.299974 -0.150114)
			(stroke
				(width 0.1)
				(type default)
			)
			(layer "F.Fab")
		)
		(fp_line
			(start 0.299974 0.150114)
			(end -0.299974 0.150114)
			(stroke
				(width 0.1)
				(type default)
			)
			(layer "F.Fab")
		)
		(fp_line
			(start -0.299974 0.150114)
			(end -0.299974 -0.150114)
			(stroke
				(width 0.1)
				(type default)
			)
			(layer "F.Fab")
		)
		(pad "1" smd rect
			(at -0.2667 0 90)
			(size 0.3048 0.381)
			(layers "F.Cu" "F.Mask" "F.Paste")
			(net "P5E_PEX0_STN5_TX_DN<81>")
		)
		(pad "2" smd rect
			(at 0.2667 0 90)
			(size 0.3048 0.381)
			(layers "F.Cu" "F.Mask" "F.Paste")
			(net "P5E_PEX0_STN5_TX_C_DN<81>")
		)
	)
	(footprint ""
		(layer "F.Cu")
		(at 318.410844 -61.386974)
		(property "Reference" "R4511"
			(at 0 0 0)
			(layer "F.SilkS")
			(hide yes)
			(effects
				(font
					(size 1.27 1.27)
				)
			)
		)
		(property "Value" ""
			(at 0 0 0)
			(layer "F.Fab")
			(effects
				(font
					(size 1.27 1.27)
				)
			)
		)
		(duplicate_pad_numbers_are_jumpers no)
		(fp_line
			(start -0.7874 -0.4064)
			(end 0.7874 -0.4064)
			(stroke
				(width 0.1524)
				(type default)
			)
			(layer "F.SilkS")
		)
		(fp_line
			(start -0.7874 0.4064)
			(end -0.7874 -0.4064)
			(stroke
				(width 0.1524)
				(type default)
			)
			(layer "F.SilkS")
		)
		(fp_line
			(start 0.7874 -0.4064)
			(end 0.7874 0.4064)
			(stroke
				(width 0.1524)
				(type default)
			)
			(layer "F.SilkS")
		)
		(fp_line
			(start 0.7874 0.4064)
			(end -0.7874 0.4064)
			(stroke
				(width 0.1524)
				(type default)
			)
			(layer "F.SilkS")
		)
		(fp_line
			(start -0.67945 -0.305054)
			(end -0.12065 -0.305054)
			(stroke
				(width 0.1)
				(type default)
			)
			(layer "F.Fab")
		)
		(fp_line
			(start -0.67945 0.3048)
			(end -0.67945 -0.305054)
			(stroke
				(width 0.1)
				(type default)
			)
			(layer "F.Fab")
		)
		(fp_line
			(start -0.12065 -0.305054)
			(end -0.12065 -0.2794)
			(stroke
				(width 0.1)
				(type default)
			)
			(layer "F.Fab")
		)
		(fp_line
			(start -0.12065 -0.2794)
			(end 0.12065 -0.2794)
			(stroke
				(width 0.1)
				(type default)
			)
			(layer "F.Fab")
		)
		(fp_line
			(start -0.12065 0.2794)
			(end -0.12065 0.3048)
			(stroke
				(width 0.1)
				(type default)
			)
			(layer "F.Fab")
		)
		(fp_line
			(start -0.12065 0.3048)
			(end -0.67945 0.3048)
			(stroke
				(width 0.1)
				(type default)
			)
			(layer "F.Fab")
		)
		(fp_line
			(start 0.120396 0.2794)
			(end -0.12065 0.2794)
			(stroke
				(width 0.1)
				(type default)
			)
			(layer "F.Fab")
		)
		(fp_line
			(start 0.120396 0.3048)
			(end 0.120396 0.2794)
			(stroke
				(width 0.1)
				(type default)
			)
			(layer "F.Fab")
		)
		(fp_line
			(start 0.12065 -0.3048)
			(end 0.67945 -0.3048)
			(stroke
				(width 0.1)
				(type default)
			)
			(layer "F.Fab")
		)
		(fp_line
			(start 0.12065 -0.2794)
			(end 0.12065 -0.3048)
			(stroke
				(width 0.1)
				(type default)
			)
			(layer "F.Fab")
		)
		(fp_line
			(start 0.67945 -0.3048)
			(end 0.67945 0.3048)
			(stroke
				(width 0.1)
				(type default)
			)
			(layer "F.Fab")
		)
		(fp_line
			(start 0.67945 0.3048)
			(end 0.120396 0.3048)
			(stroke
				(width 0.1)
				(type default)
			)
			(layer "F.Fab")
		)
		(pad "1" smd circle
			(at -0.40005 0)
			(size 0 0)
			(layers "F.Cu" "F.Mask" "F.Paste")
			(net "PWRGD_P3V3_SSD11")
		)
		(pad "2" smd circle
			(at 0.40005 0)
			(size 0 0)
			(layers "F.Cu" "F.Mask" "F.Paste")
			(net "PWRGD_P3V3_SSD11_R")
		)
	)
	(footprint ""
		(layer "F.Cu")
		(at 55.9816 -157.8356)
		(property "Reference" "R48"
			(at 0 0 0)
			(layer "F.SilkS")
			(hide yes)
			(effects
				(font
					(size 1.27 1.27)
				)
			)
		)
		(property "Value" ""
			(at 0 0 0)
			(layer "F.Fab")
			(effects
				(font
					(size 1.27 1.27)
				)
			)
		)
		(duplicate_pad_numbers_are_jumpers no)
		(fp_line
			(start -0.7874 -0.4064)
			(end 0.7874 -0.4064)
			(stroke
				(width 0.1524)
				(type default)
			)
			(layer "F.SilkS")
		)
		(fp_line
			(start -0.7874 0.4064)
			(end -0.7874 -0.4064)
			(stroke
				(width 0.1524)
				(type default)
			)
			(layer "F.SilkS")
		)
		(fp_line
			(start 0.7874 -0.4064)
			(end 0.7874 0.4064)
			(stroke
				(width 0.1524)
				(type default)
			)
			(layer "F.SilkS")
		)
		(fp_line
			(start 0.7874 0.4064)
			(end -0.7874 0.4064)
			(stroke
				(width 0.1524)
				(type default)
			)
			(layer "F.SilkS")
		)
		(fp_line
			(start -0.67945 -0.305054)
			(end -0.12065 -0.305054)
			(stroke
				(width 0.1)
				(type default)
			)
			(layer "F.Fab")
		)
		(fp_line
			(start -0.67945 0.3048)
			(end -0.67945 -0.305054)
			(stroke
				(width 0.1)
				(type default)
			)
			(layer "F.Fab")
		)
		(fp_line
			(start -0.12065 -0.305054)
			(end -0.12065 -0.2794)
			(stroke
				(width 0.1)
				(type default)
			)
			(layer "F.Fab")
		)
		(fp_line
			(start -0.12065 -0.2794)
			(end 0.12065 -0.2794)
			(stroke
				(width 0.1)
				(type default)
			)
			(layer "F.Fab")
		)
		(fp_line
			(start -0.12065 0.2794)
			(end -0.12065 0.3048)
			(stroke
				(width 0.1)
				(type default)
			)
			(layer "F.Fab")
		)
		(fp_line
			(start -0.12065 0.3048)
			(end -0.67945 0.3048)
			(stroke
				(width 0.1)
				(type default)
			)
			(layer "F.Fab")
		)
		(fp_line
			(start 0.120396 0.2794)
			(end -0.12065 0.2794)
			(stroke
				(width 0.1)
				(type default)
			)
			(layer "F.Fab")
		)
		(fp_line
			(start 0.120396 0.3048)
			(end 0.120396 0.2794)
			(stroke
				(width 0.1)
				(type default)
			)
			(layer "F.Fab")
		)
		(fp_line
			(start 0.12065 -0.3048)
			(end 0.67945 -0.3048)
			(stroke
				(width 0.1)
				(type default)
			)
			(layer "F.Fab")
		)
		(fp_line
			(start 0.12065 -0.2794)
			(end 0.12065 -0.3048)
			(stroke
				(width 0.1)
				(type default)
			)
			(layer "F.Fab")
		)
		(fp_line
			(start 0.67945 -0.3048)
			(end 0.67945 0.3048)
			(stroke
				(width 0.1)
				(type default)
			)
			(layer "F.Fab")
		)
		(fp_line
			(start 0.67945 0.3048)
			(end 0.120396 0.3048)
			(stroke
				(width 0.1)
				(type default)
			)
			(layer "F.Fab")
		)
		(pad "1" smd circle
			(at -0.40005 0)
			(size 0 0)
			(layers "F.Cu" "F.Mask" "F.Paste")
			(net "RST_NIC0_PERST3_R_N")
		)
		(pad "2" smd circle
			(at 0.40005 0)
			(size 0 0)
			(layers "F.Cu" "F.Mask" "F.Paste")
			(net "RST_HP_NIC0_BUF_N")
		)
	)
)
